(kicad_pcb
	(version 20240108)
	(generator "pcbnew")
	(generator_version "8.0")
	(general
		(thickness 1.62)
		(legacy_teardrops no)
	)
	(paper "A4")
	(title_block
		(title "Jetson Orin Baseboard")
		(date "2025-03-12")
		(rev "1.3.4")
		(company "Antmicro Ltd")
		(comment 1 "www.antmicro.com")
		(comment 9 "footprints 402-407 of 677")
	)
	(layers
		(0 "F.Cu" signal)
		(1 "In1.Cu" signal)
		(2 "In2.Cu" signal)
		(3 "In3.Cu" signal)
		(4 "In4.Cu" jumper)
		(5 "In5.Cu" signal)
		(6 "In6.Cu" signal)
		(31 "B.Cu" signal)
		(32 "B.Adhes" user "B.Adhesive")
		(33 "F.Adhes" user "F.Adhesive")
		(34 "B.Paste" user)
		(35 "F.Paste" user)
		(36 "B.SilkS" user "B.Silkscreen")
		(37 "F.SilkS" user "F.Silkscreen")
		(38 "B.Mask" user)
		(39 "F.Mask" user)
		(40 "Dwgs.User" user "User.Drawings")
		(41 "Cmts.User" user "User.Comments")
		(42 "Eco1.User" user "User.Eco1")
		(43 "Eco2.User" user "User.Eco2")
		(44 "Edge.Cuts" user)
		(45 "Margin" user)
		(46 "B.CrtYd" user "B.Courtyard")
		(47 "F.CrtYd" user "F.Courtyard")
		(48 "B.Fab" user)
		(49 "F.Fab" user)
	)
	(footprint "antmicro-footprints:C_0402_1005Metric"
		(layer "B.Cu")
		(at 61.5 107.2 -90)
		(descr "Capacitor SMD 0402")
		(tags "capacitor SMD 0402")
		(property "Reference" "C64"
			(at -1.04 -1.23 90)
			(layer "B.SilkS")
			(effects
				(font
					(size 0.7 0.7)
					(thickness 0.15)
				)
				(justify left bottom mirror)
			)
		)
		(property "Value" "C_100n_0402"
			(at 0 -1.4 90)
			(layer "B.Fab")
			(effects
				(font
					(size 0.7 0.7)
					(thickness 0.15)
				)
				(justify left bottom mirror)
			)
		)
		(property "Footprint" "antmicro-footprints:C_0402_1005Metric"
			(at 0 0 -90)
			(layer "F.Fab")
			(hide yes)
			(effects
				(font
					(size 1.27 1.27)
					(thickness 0.15)
				)
			)
		)
		(property "Datasheet" "https://www.murata.com/products/productdetail?partno=GRM155R61H104KE14%23"
			(at 0 0 -90)
			(layer "F.Fab")
			(hide yes)
			(effects
				(font
					(size 1.27 1.27)
					(thickness 0.15)
				)
			)
		)
		(property "Author" "Antmicro"
			(at -45.7 168.7 0)
			(layer "B.Fab")
			(hide yes)
			(effects
				(font
					(size 1 1)
					(thickness 0.15)
				)
				(justify mirror)
			)
		)
		(property "Dielectric" "X5R"
			(at -45.7 168.7 0)
			(layer "B.Fab")
			(hide yes)
			(effects
				(font
					(size 1 1)
					(thickness 0.15)
				)
				(justify mirror)
			)
		)
		(property "License" "Apache-2.0"
			(at -45.7 168.7 0)
			(layer "B.Fab")
			(hide yes)
			(effects
				(font
					(size 1 1)
					(thickness 0.15)
				)
				(justify mirror)
			)
		)
		(property "MPN" "GRM155R61H104KE14D"
			(at -45.7 168.7 0)
			(layer "B.Fab")
			(hide yes)
			(effects
				(font
					(size 1 1)
					(thickness 0.15)
				)
				(justify mirror)
			)
		)
		(property "Manufacturer" "Murata"
			(at -45.7 168.7 0)
			(layer "B.Fab")
			(hide yes)
			(effects
				(font
					(size 1 1)
					(thickness 0.15)
				)
				(justify mirror)
			)
		)
		(property "Val" "100n"
			(at -45.7 168.7 0)
			(layer "B.Fab")
			(hide yes)
			(effects
				(font
					(size 1 1)
					(thickness 0.15)
				)
				(justify mirror)
			)
		)
		(property "Voltage" "50V"
			(at -45.7 168.7 0)
			(layer "B.Fab")
			(hide yes)
			(effects
				(font
					(size 1 1)
					(thickness 0.15)
				)
				(justify mirror)
			)
		)
		(sheetname "USB Debug, DP")
		(sheetfile "usb.kicad_sch")
		(attr smd)
		(fp_rect
			(start -0.925 0.47)
			(end 0.925 -0.47)
			(stroke
				(width 0.05)
				(type default)
			)
			(fill none)
			(layer "B.CrtYd")
		)
		(fp_line
			(start -0.494 0.25)
			(end -0.494 -0.248)
			(stroke
				(width 0.15)
				(type solid)
			)
			(layer "B.Fab")
		)
		(fp_line
			(start 0.504 0.25)
			(end -0.494 0.25)
			(stroke
				(width 0.15)
				(type solid)
			)
			(layer "B.Fab")
		)
		(fp_line
			(start -0.494 -0.248)
			(end 0.504 -0.248)
			(stroke
				(width 0.15)
				(type solid)
			)
			(layer "B.Fab")
		)
		(fp_line
			(start 0.504 -0.248)
			(end 0.504 0.25)
			(stroke
				(width 0.15)
				(type solid)
			)
			(layer "B.Fab")
		)
		(fp_text user "${REFERENCE}"
			(at -0.932 -3.168 90)
			(layer "B.Fab")
			(hide yes)
			(effects
				(font
					(size 0.7 0.7)
					(thickness 0.15)
				)
				(justify left bottom mirror)
			)
		)
		(fp_text user "Author: Antmicro"
			(at -0.932 -4.17 90)
			(layer "B.Fab")
			(hide yes)
			(effects
				(font
					(size 0.7 0.7)
					(thickness 0.15)
				)
				(justify left bottom mirror)
			)
		)
		(fp_text user "License: Apache-2.0"
			(at -0.932 -5.17 90)
			(layer "B.Fab")
			(hide yes)
			(effects
				(font
					(size 0.7 0.7)
					(thickness 0.15)
				)
				(justify left bottom mirror)
			)
		)
		(pad "1" smd roundrect
			(at -0.48 0 270)
			(size 0.59 0.64)
			(layers "B.Cu" "B.Paste" "B.Mask")
			(roundrect_rratio 0.25)
			(net 196 "/USB Debug, DP/USBC3_VBUS")
			(pintype "passive")
		)
		(pad "2" smd roundrect
			(at 0.48 0 270)
			(size 0.59 0.64)
			(layers "B.Cu" "B.Paste" "B.Mask")
			(roundrect_rratio 0.25)
			(net 1 "GND")
			(pintype "passive")
		)
	)
	(footprint "antmicro-footprints:TP_SMD_0.75mm"
		(layer "B.Cu")
		(at 70 96.4)
		(property "Reference" "TP18"
			(at 3.36 1 0)
			(layer "B.SilkS")
			(hide yes)
			(effects
				(font
					(size 0.7 0.7)
					(thickness 0.15)
				)
				(justify left bottom mirror)
			)
		)
		(property "Value" "TP_0.75mm_SMD"
			(at 0 -1.2 180)
			(layer "B.Fab")
			(effects
				(font
					(size 0.7 0.7)
					(thickness 0.15)
				)
				(justify left bottom mirror)
			)
		)
		(property "Footprint" "antmicro-footprints:TP_SMD_0.75mm"
			(at 0 0 0)
			(layer "F.Fab")
			(hide yes)
			(effects
				(font
					(size 1.27 1.27)
					(thickness 0.15)
				)
			)
		)
		(property "Author" "Antmicro"
			(at 0 0 0)
			(layer "B.Fab")
			(hide yes)
			(effects
				(font
					(size 1 1)
					(thickness 0.15)
				)
				(justify mirror)
			)
		)
		(property "License" "Apache-2.0"
			(at 0 0 0)
			(layer "B.Fab")
			(hide yes)
			(effects
				(font
					(size 1 1)
					(thickness 0.15)
				)
				(justify mirror)
			)
		)
		(property "MPN" ""
			(at 0 0 0)
			(layer "B.Fab")
			(hide yes)
			(effects
				(font
					(size 1 1)
					(thickness 0.15)
				)
				(justify mirror)
			)
		)
		(property "Manufacturer" ""
			(at 0 0 0)
			(layer "B.Fab")
			(hide yes)
			(effects
				(font
					(size 1 1)
					(thickness 0.15)
				)
				(justify mirror)
			)
		)
		(sheetname "USB Debug, DP")
		(sheetfile "usb.kicad_sch")
		(attr exclude_from_pos_files exclude_from_bom)
		(fp_circle
			(center 0 0)
			(end 0.475 0)
			(stroke
				(width 0.05)
				(type default)
			)
			(fill none)
			(layer "B.CrtYd")
		)
		(fp_text user "${REFERENCE}"
			(at -0.4 -2.7 180)
			(layer "B.Fab")
			(hide yes)
			(effects
				(font
					(size 0.7 0.7)
					(thickness 0.15)
				)
				(justify left bottom mirror)
			)
		)
		(fp_text user "Author: Antmicro"
			(at -0.4 -3.901 180)
			(layer "B.Fab")
			(hide yes)
			(effects
				(font
					(size 0.7 0.7)
					(thickness 0.15)
				)
				(justify left bottom mirror)
			)
		)
		(fp_text user "License: Apache-2.0"
			(at -0.4 -5.101 180)
			(layer "B.Fab")
			(hide yes)
			(effects
				(font
					(size 0.7 0.7)
					(thickness 0.15)
				)
				(justify left bottom mirror)
			)
		)
		(pad "1" smd circle
			(at 0 0)
			(size 0.75 0.75)
			(layers "B.Cu" "B.Mask")
			(net 394 "/USB Debug, DP/PDC_I2C2_IRQn")
			(pinfunction "1")
			(pintype "passive")
		)
	)
	(footprint "antmicro-footprints:SOD-523"
		(layer "B.Cu")
		(at 68.85 97.71 180)
		(property "Reference" "D35"
			(at -0.89 -1.48 0)
			(layer "B.SilkS")
			(effects
				(font
					(size 0.7 0.7)
					(thickness 0.15)
				)
				(justify left bottom mirror)
			)
		)
		(property "Value" "RB521S30T1G"
			(at 0 -1.499 0)
			(layer "B.Fab")
			(effects
				(font
					(size 0.7 0.7)
					(thickness 0.15)
				)
				(justify left bottom mirror)
			)
		)
		(property "Footprint" "antmicro-footprints:SOD-523"
			(at 0 0 180)
			(layer "F.Fab")
			(hide yes)
			(effects
				(font
					(size 1.27 1.27)
					(thickness 0.15)
				)
			)
		)
		(property "Datasheet" "https://www.onsemi.com/pdf/datasheet/rb521s30t1-d.pdf"
			(at 0 0 180)
			(layer "F.Fab")
			(hide yes)
			(effects
				(font
					(size 1.27 1.27)
					(thickness 0.15)
				)
			)
		)
		(property "Author" "Antmicro"
			(at 137.7 195.42 0)
			(layer "B.Fab")
			(hide yes)
			(effects
				(font
					(size 1 1)
					(thickness 0.15)
				)
				(justify mirror)
			)
		)
		(property "License" "Apache-2.0"
			(at 137.7 195.42 0)
			(layer "B.Fab")
			(hide yes)
			(effects
				(font
					(size 1 1)
					(thickness 0.15)
				)
				(justify mirror)
			)
		)
		(property "MPN" "RB521S30T1G"
			(at 137.7 195.42 0)
			(layer "B.Fab")
			(hide yes)
			(effects
				(font
					(size 1 1)
					(thickness 0.15)
				)
				(justify mirror)
			)
		)
		(property "Manufacturer" "ON Semiconductor"
			(at 137.7 195.42 0)
			(layer "B.Fab")
			(hide yes)
			(effects
				(font
					(size 1 1)
					(thickness 0.15)
				)
				(justify mirror)
			)
		)
		(sheetname "USB Debug, DP")
		(sheetfile "usb.kicad_sch")
		(attr smd)
		(fp_line
			(start -0.35 -0.5)
			(end -0.35 0.5)
			(stroke
				(width 0.15)
				(type solid)
			)
			(layer "B.SilkS")
		)
		(fp_rect
			(start -1 0.6)
			(end 1 -0.6)
			(stroke
				(width 0.05)
				(type solid)
			)
			(fill none)
			(layer "B.CrtYd")
		)
		(fp_line
			(start 0.65 0.425)
			(end -0.652 0.425)
			(stroke
				(width 0.15)
				(type solid)
			)
			(layer "B.Fab")
		)
		(fp_line
			(start 0.65 -0.423)
			(end 0.65 0.425)
			(stroke
				(width 0.15)
				(type solid)
			)
			(layer "B.Fab")
		)
		(fp_line
			(start 0.65 -0.423)
			(end -0.652 -0.423)
			(stroke
				(width 0.15)
				(type solid)
			)
			(layer "B.Fab")
		)
		(fp_line
			(start -0.35 -0.4)
			(end -0.35 0.4)
			(stroke
				(width 0.15)
				(type solid)
			)
			(layer "B.Fab")
		)
		(fp_line
			(start -0.652 0.425)
			(end -0.652 -0.423)
			(stroke
				(width 0.15)
				(type solid)
			)
			(layer "B.Fab")
		)
		(fp_text user "${REFERENCE}"
			(at -1.276 -3.499 0)
			(layer "B.Fab")
			(hide yes)
			(effects
				(font
					(size 0.7 0.7)
					(thickness 0.15)
				)
				(justify left bottom mirror)
			)
		)
		(fp_text user "License: Apache-2.0"
			(at -1.276 -5.9 0)
			(layer "B.Fab")
			(hide yes)
			(effects
				(font
					(size 0.7 0.7)
					(thickness 0.15)
				)
				(justify left bottom mirror)
			)
		)
		(fp_text user "Author: Antmicro"
			(at -1.276 -4.7 0)
			(layer "B.Fab")
			(hide yes)
			(effects
				(font
					(size 0.7 0.7)
					(thickness 0.15)
				)
				(justify left bottom mirror)
			)
		)
		(pad "1" smd roundrect
			(at -0.701 0 180)
			(size 0.5 0.6)
			(layers "B.Cu" "B.Paste" "B.Mask")
			(roundrect_rratio 0.25)
			(net 98 "EEPROM_PWR")
			(pinfunction "C")
			(pintype "passive")
		)
		(pad "2" smd roundrect
			(at 0.699 0 180)
			(size 0.5 0.6)
			(layers "B.Cu" "B.Paste" "B.Mask")
			(roundrect_rratio 0.25)
			(net 134 "/USB Debug, DP/PDC_LDO_3V3")
			(pinfunction "A")
			(pintype "passive")
		)
	)
	(footprint "antmicro-footprints:R_0402_1005Metric"
		(layer "B.Cu")
		(at 102.7 76.7 180)
		(descr "Resistor SMD 0402")
		(tags "resistor SMD 0402")
		(property "Reference" "R206"
			(at -3.7 -0.45 0)
			(layer "B.SilkS")
			(effects
				(font
					(size 0.7 0.7)
					(thickness 0.15)
				)
				(justify left bottom mirror)
			)
		)
		(property "Value" "R_470R_0402"
			(at 0 -1.4 0)
			(layer "B.Fab")
			(effects
				(font
					(size 0.7 0.7)
					(thickness 0.15)
				)
				(justify left bottom mirror)
			)
		)
		(property "Footprint" "antmicro-footprints:R_0402_1005Metric"
			(at 0 0 180)
			(layer "F.Fab")
			(hide yes)
			(effects
				(font
					(size 1.27 1.27)
					(thickness 0.15)
				)
			)
		)
		(property "Datasheet" "https://www.bourns.com/docs/product-datasheets/cr.pdf"
			(at 0 0 180)
			(layer "F.Fab")
			(hide yes)
			(effects
				(font
					(size 1.27 1.27)
					(thickness 0.15)
				)
			)
		)
		(property "Author" "Antmicro"
			(at 205.4 153.4 0)
			(layer "B.Fab")
			(hide yes)
			(effects
				(font
					(size 1 1)
					(thickness 0.15)
				)
				(justify mirror)
			)
		)
		(property "License" "Apache-2.0"
			(at 205.4 153.4 0)
			(layer "B.Fab")
			(hide yes)
			(effects
				(font
					(size 1 1)
					(thickness 0.15)
				)
				(justify mirror)
			)
		)
		(property "MPN" "CR0402-FX-4700GLF"
			(at 205.4 153.4 0)
			(layer "B.Fab")
			(hide yes)
			(effects
				(font
					(size 1 1)
					(thickness 0.15)
				)
				(justify mirror)
			)
		)
		(property "Manufacturer" "Bourns"
			(at 205.4 153.4 0)
			(layer "B.Fab")
			(hide yes)
			(effects
				(font
					(size 1 1)
					(thickness 0.15)
				)
				(justify mirror)
			)
		)
		(property "Tolerance" "1%"
			(at 205.4 153.4 0)
			(layer "B.Fab")
			(hide yes)
			(effects
				(font
					(size 1 1)
					(thickness 0.15)
				)
				(justify mirror)
			)
		)
		(property "Val" "470R"
			(at 205.4 153.4 0)
			(layer "B.Fab")
			(hide yes)
			(effects
				(font
					(size 1 1)
					(thickness 0.15)
				)
				(justify mirror)
			)
		)
		(sheetname "CSI")
		(sheetfile "csi.kicad_sch")
		(attr smd)
		(fp_rect
			(start -0.925 0.47)
			(end 0.925 -0.47)
			(stroke
				(width 0.05)
				(type default)
			)
			(fill none)
			(layer "B.CrtYd")
		)
		(fp_rect
			(start -0.5 0.25)
			(end 0.5 -0.25)
			(stroke
				(width 0.15)
				(type solid)
			)
			(fill none)
			(layer "B.Fab")
		)
		(fp_text user "${REFERENCE}"
			(at -0.95 -3.168 0)
			(layer "B.Fab")
			(hide yes)
			(effects
				(font
					(size 0.7 0.7)
					(thickness 0.15)
				)
				(justify left bottom mirror)
			)
		)
		(fp_text user "License: Apache-2.0"
			(at -0.95 -5.169 0)
			(layer "B.Fab")
			(hide yes)
			(effects
				(font
					(size 0.7 0.7)
					(thickness 0.15)
				)
				(justify left bottom mirror)
			)
		)
		(fp_text user "Author: Antmicro"
			(at -0.95 -4.169 0)
			(layer "B.Fab")
			(hide yes)
			(effects
				(font
					(size 0.7 0.7)
					(thickness 0.15)
				)
				(justify left bottom mirror)
			)
		)
		(pad "1" smd roundrect
			(at -0.48 0 180)
			(size 0.59 0.64)
			(layers "B.Cu" "B.Paste" "B.Mask")
			(roundrect_rratio 0.25)
			(net 162 "Net-(D25-A)")
			(pintype "passive")
		)
		(pad "2" smd roundrect
			(at 0.48 0 180)
			(size 0.59 0.64)
			(layers "B.Cu" "B.Paste" "B.Mask")
			(roundrect_rratio 0.25)
			(net 111 "/CSI/CSIB_5V")
			(pintype "passive")
		)
	)
	(footprint "antmicro-footprints:TP_SMD_0.75mm"
		(layer "B.Cu")
		(at 68.165 127.57 180)
		(property "Reference" "TP23"
			(at -1.3 0.55 0)
			(layer "B.SilkS")
			(hide yes)
			(effects
				(font
					(size 0.7 0.7)
					(thickness 0.15)
				)
				(justify left bottom mirror)
			)
		)
		(property "Value" "TP_0.75mm_SMD"
			(at 0 -1.2 0)
			(layer "B.Fab")
			(effects
				(font
					(size 0.7 0.7)
					(thickness 0.15)
				)
				(justify left bottom mirror)
			)
		)
		(property "Footprint" "antmicro-footprints:TP_SMD_0.75mm"
			(at 0 0 180)
			(layer "F.Fab")
			(hide yes)
			(effects
				(font
					(size 1.27 1.27)
					(thickness 0.15)
				)
			)
		)
		(property "Author" "Antmicro"
			(at 136.33 255.14 0)
			(layer "B.Fab")
			(hide yes)
			(effects
				(font
					(size 1 1)
					(thickness 0.15)
				)
				(justify mirror)
			)
		)
		(property "License" "Apache-2.0"
			(at 136.33 255.14 0)
			(layer "B.Fab")
			(hide yes)
			(effects
				(font
					(size 1 1)
					(thickness 0.15)
				)
				(justify mirror)
			)
		)
		(property "MPN" ""
			(at 136.33 255.14 0)
			(layer "B.Fab")
			(hide yes)
			(effects
				(font
					(size 1 1)
					(thickness 0.15)
				)
				(justify mirror)
			)
		)
		(property "Manufacturer" ""
			(at 136.33 255.14 0)
			(layer "B.Fab")
			(hide yes)
			(effects
				(font
					(size 1 1)
					(thickness 0.15)
				)
				(justify mirror)
			)
		)
		(sheetname "Supply")
		(sheetfile "supply.kicad_sch")
		(attr exclude_from_pos_files exclude_from_bom)
		(fp_circle
			(center 0 0)
			(end 0.475 0)
			(stroke
				(width 0.05)
				(type default)
			)
			(fill none)
			(layer "B.CrtYd")
		)
		(fp_text user "License: Apache-2.0"
			(at -0.4 -5.101 0)
			(layer "B.Fab")
			(hide yes)
			(effects
				(font
					(size 0.7 0.7)
					(thickness 0.15)
				)
				(justify left bottom mirror)
			)
		)
		(fp_text user "${REFERENCE}"
			(at -0.4 -2.7 0)
			(layer "B.Fab")
			(hide yes)
			(effects
				(font
					(size 0.7 0.7)
					(thickness 0.15)
				)
				(justify left bottom mirror)
			)
		)
		(fp_text user "Author: Antmicro"
			(at -0.4 -3.901 0)
			(layer "B.Fab")
			(hide yes)
			(effects
				(font
					(size 0.7 0.7)
					(thickness 0.15)
				)
				(justify left bottom mirror)
			)
		)
		(pad "1" smd circle
			(at 0 0 180)
			(size 0.75 0.75)
			(layers "B.Cu" "B.Mask")
			(net 1 "GND")
			(pinfunction "1")
			(pintype "passive")
		)
	)
	(footprint "antmicro-footprints:SOD-523"
		(layer "B.Cu")
		(at 56.6 78.8)
		(property "Reference" "D37"
			(at 20.01 9.2 0)
			(layer "B.SilkS")
			(effects
				(font
					(size 0.7 0.7)
					(thickness 0.15)
				)
				(justify right bottom mirror)
			)
		)
		(property "Value" "RB521S30T1G"
			(at 0 -1.499 0)
			(layer "B.Fab")
			(effects
				(font
					(size 0.7 0.7)
					(thickness 0.15)
				)
				(justify right bottom mirror)
			)
		)
		(property "Footprint" "antmicro-footprints:SOD-523"
			(at 0 0 0)
			(layer "F.Fab")
			(hide yes)
			(effects
				(font
					(size 1.27 1.27)
					(thickness 0.15)
				)
			)
		)
		(property "Datasheet" "https://www.onsemi.com/pdf/datasheet/rb521s30t1-d.pdf"
			(at 0 0 0)
			(layer "F.Fab")
			(hide yes)
			(effects
				(font
					(size 1.27 1.27)
					(thickness 0.15)
				)
			)
		)
		(property "Author" "Antmicro"
			(at 0 0 0)
			(layer "B.Fab")
			(hide yes)
			(effects
				(font
					(size 1 1)
					(thickness 0.15)
				)
				(justify mirror)
			)
		)
		(property "License" "Apache-2.0"
			(at 0 0 0)
			(layer "B.Fab")
			(hide yes)
			(effects
				(font
					(size 1 1)
					(thickness 0.15)
				)
				(justify mirror)
			)
		)
		(property "MPN" "RB521S30T1G"
			(at 0 0 0)
			(layer "B.Fab")
			(hide yes)
			(effects
				(font
					(size 1 1)
					(thickness 0.15)
				)
				(justify mirror)
			)
		)
		(property "Manufacturer" "ON Semiconductor"
			(at 0 0 0)
			(layer "B.Fab")
			(hide yes)
			(effects
				(font
					(size 1 1)
					(thickness 0.15)
				)
				(justify mirror)
			)
		)
		(sheetname "Supply")
		(sheetfile "supply.kicad_sch")
		(attr smd)
		(fp_line
			(start -0.35 -0.5)
			(end -0.35 0.5)
			(stroke
				(width 0.15)
				(type solid)
			)
			(layer "B.SilkS")
		)
		(fp_rect
			(start -1 0.6)
			(end 1 -0.6)
			(stroke
				(width 0.05)
				(type solid)
			)
			(fill none)
			(layer "B.CrtYd")
		)
		(fp_line
			(start -0.652 0.425)
			(end -0.652 -0.423)
			(stroke
				(width 0.15)
				(type solid)
			)
			(layer "B.Fab")
		)
		(fp_line
			(start -0.35 -0.4)
			(end -0.35 0.4)
			(stroke
				(width 0.15)
				(type solid)
			)
			(layer "B.Fab")
		)
		(fp_line
			(start 0.65 -0.423)
			(end -0.652 -0.423)
			(stroke
				(width 0.15)
				(type solid)
			)
			(layer "B.Fab")
		)
		(fp_line
			(start 0.65 -0.423)
			(end 0.65 0.425)
			(stroke
				(width 0.15)
				(type solid)
			)
			(layer "B.Fab")
		)
		(fp_line
			(start 0.65 0.425)
			(end -0.652 0.425)
			(stroke
				(width 0.15)
				(type solid)
			)
			(layer "B.Fab")
		)
		(fp_text user "Author: Antmicro"
			(at -1.276 -4.7 0)
			(layer "B.Fab")
			(hide yes)
			(effects
				(font
					(size 0.7 0.7)
					(thickness 0.15)
				)
				(justify right bottom mirror)
			)
		)
		(fp_text user "${REFERENCE}"
			(at -1.276 -3.499 0)
			(layer "B.Fab")
			(hide yes)
			(effects
				(font
					(size 0.7 0.7)
					(thickness 0.15)
				)
				(justify right bottom mirror)
			)
		)
		(fp_text user "License: Apache-2.0"
			(at -1.276 -5.9 0)
			(layer "B.Fab")
			(hide yes)
			(effects
				(font
					(size 0.7 0.7)
					(thickness 0.15)
				)
				(justify right bottom mirror)
			)
		)
		(pad "1" smd roundrect
			(at -0.701 0)
			(size 0.5 0.6)
			(layers "B.Cu" "B.Paste" "B.Mask")
			(roundrect_rratio 0.25)
			(net 342 "Net-(D37-C)")
			(pinfunction "C")
			(pintype "passive")
		)
		(pad "2" smd roundrect
			(at 0.699 0)
			(size 0.5 0.6)
			(layers "B.Cu" "B.Paste" "B.Mask")
			(roundrect_rratio 0.25)
			(net 629 "Net-(D37-A)")
			(pinfunction "A")
			(pintype "passive")
		)
	)
)
